# S9S_MB_2U (Grand Teton) — schematic netlist excerpt (pin names and nets, part order shuffled) for the footprints in the layout excerpt that follows; sources: Cadence DE-HDL packaged netlist, KiCad conversion of 03242023_DA0F0TMBIJ0_F0T_Motherboard_J_brd_V01_OCP.brd

C1896  Q_CAP  0.01UF 50V 10% X7R  pkg C0402  page 217 : A = P3V3_AUX_FPGA_VCCIO1 ; B = GND
C2453  Q_CAP  1000PF 50V 5% EMPTY  pkg 0402  page 292 : A = PWRGD_PVCCFA_EHV_CPU1_R ; B = GND

(kicad_pcb
	(version 20260206)
	(generator "pcbnew")
	(generator_version "10.0")
	(general
		(thickness 1.6)
		(legacy_teardrops no)
	)
	(paper "A4")
	(title_block
		(title "03242023_DA0F0TMBIJ0_F0T_Motherboard_J_brd_V01_OCP.brd")
		(comment 1 "Grand Teton / footprints 4491-4492 of 6105")
	)
	(layers
		(0 "F.Cu" signal "TOP")
		(4 "In1.Cu" signal "GND")
		(6 "In2.Cu" signal "IN1")
		(8 "In3.Cu" signal "GND1")
		(10 "In4.Cu" signal "IN2")
		(12 "In5.Cu" signal "GND2")
		(14 "In6.Cu" signal "IN3")
		(16 "In7.Cu" signal "GND3")
		(18 "In8.Cu" signal "VCC")
		(20 "In9.Cu" signal "VCC1")
		(22 "In10.Cu" signal "GND4")
		(24 "In11.Cu" signal "IN4")
		(26 "In12.Cu" signal "GND5")
		(28 "In13.Cu" signal "IN5")
		(30 "In14.Cu" signal "GND6")
		(32 "In15.Cu" signal "IN6")
		(34 "In16.Cu" signal "GND7")
		(2 "B.Cu" signal "BOTTOM")
		(9 "F.Adhes" user "F.Adhesive")
		(11 "B.Adhes" user "B.Adhesive")
		(13 "F.Paste" user "Package Geometry/Pastemask Top")
		(15 "B.Paste" user "Package Geometry/Pastemask Bottom")
		(5 "F.SilkS" user "Ref Des/Silkscreen Top")
		(7 "B.SilkS" user "Ref Des/Silkscreen Bottom")
		(1 "F.Mask" user "Board Geometry/Soldermask Top")
		(3 "B.Mask" user "Board Geometry/Soldermask Bottom")
		(17 "Dwgs.User" user "User.Drawings")
		(19 "Cmts.User" user "User.Comments")
		(21 "Eco1.User" user "User.Eco1")
		(23 "Eco2.User" user "User.Eco2")
		(25 "Edge.Cuts" user "Board Geometry/Outline")
		(27 "Margin" user)
		(31 "F.CrtYd" user "Package Geometry/Place Bound Top")
		(29 "B.CrtYd" user "Package Geometry/Place Bound Bottom")
		(35 "F.Fab" user "Ref Des/Assembly Top")
		(33 "B.Fab" user "Ref Des/Assembly Bottom")
	)
	(footprint ""
		(layer "B.Cu")
		(at 174.155608 -121.375424 -90)
		(property "Reference" "C1896"
			(at 0 0 90)
			(layer "B.SilkS")
			(hide yes)
			(effects
				(font
					(size 1.27 1.27)
				)
				(justify mirror)
			)
		)
		(property "Value" ""
			(at 0 0 90)
			(layer "B.Fab")
			(effects
				(font
					(size 1.27 1.27)
				)
				(justify mirror)
			)
		)
		(duplicate_pad_numbers_are_jumpers no)
		(fp_line
			(start -0.69215 0.2921)
			(end 0.69215 0.2921)
			(stroke
				(width 0.1524)
				(type default)
			)
			(layer "B.SilkS")
		)
		(fp_line
			(start 0.69215 0.2921)
			(end 0.69215 -0.2921)
			(stroke
				(width 0.1524)
				(type default)
			)
			(layer "B.SilkS")
		)
		(fp_line
			(start -0.69215 -0.2921)
			(end -0.69215 0.2921)
			(stroke
				(width 0.1524)
				(type default)
			)
			(layer "B.SilkS")
		)
		(fp_line
			(start 0.69215 -0.2921)
			(end -0.69215 -0.2921)
			(stroke
				(width 0.1524)
				(type default)
			)
			(layer "B.SilkS")
		)
		(fp_line
			(start -0.51435 0.2794)
			(end 0.51435 0.2794)
			(stroke
				(width 0.1)
				(type default)
			)
			(layer "B.Fab")
		)
		(fp_line
			(start 0.51435 0.2794)
			(end 0.51435 -0.2794)
			(stroke
				(width 0.1)
				(type default)
			)
			(layer "B.Fab")
		)
		(fp_line
			(start -0.51435 -0.2794)
			(end -0.51435 0.2794)
			(stroke
				(width 0.1)
				(type default)
			)
			(layer "B.Fab")
		)
		(fp_line
			(start 0.51435 -0.2794)
			(end -0.51435 -0.2794)
			(stroke
				(width 0.1)
				(type default)
			)
			(layer "B.Fab")
		)
		(pad "1" smd circle
			(at 0.40005 0 90)
			(size 0 0)
			(layers "B.Cu" "B.Mask" "B.Paste")
			(net "P3V3_AUX_FPGA_VCCIO1")
		)
		(pad "2" smd circle
			(at -0.40005 0 90)
			(size 0 0)
			(layers "B.Cu" "B.Mask" "B.Paste")
			(net "GND")
		)
		(zone
			(layer "B.Cu")
			(hatch none 0.5)
			(connect_pads
				(clearance 0)
			)
			(min_thickness 0.25)
			(keepout
				(tracks not_allowed)
				(vias allowed)
				(pads allowed)
				(copperpour not_allowed)
				(footprints allowed)
			)
			(placement
				(enabled no)
				(sheetname "")
			)
			(fill
				(thermal_gap 0.5)
				(thermal_bridge_width 0.5)
				(island_removal_mode 0)
			)
			(polygon
				(pts
					(xy 174.067978 -121.184924) (xy 174.009812 -121.276364) (xy 174.009812 -121.475754) (xy 174.067978 -121.565924)
					(xy 174.243238 -121.565924) (xy 174.301658 -121.475754) (xy 174.301658 -121.276364) (xy 174.243492 -121.184924)
				)
			)
		)
	)
	(footprint ""
		(layer "B.Cu")
		(at 36.956492 -132.783834 180)
		(property "Reference" "C2453"
			(at 0 0 0)
			(layer "B.SilkS")
			(hide yes)
			(effects
				(font
					(size 1.27 1.27)
				)
				(justify mirror)
			)
		)
		(property "Value" ""
			(at 0 0 0)
			(layer "B.Fab")
			(effects
				(font
					(size 1.27 1.27)
				)
				(justify mirror)
			)
		)
		(duplicate_pad_numbers_are_jumpers no)
		(fp_line
			(start 0.7874 0.4064)
			(end 0.7874 -0.4064)
			(stroke
				(width 0.1524)
				(type default)
			)
			(layer "B.SilkS")
		)
		(fp_line
			(start 0.7874 -0.4064)
			(end -0.7874 -0.4064)
			(stroke
				(width 0.1524)
				(type default)
			)
			(layer "B.SilkS")
		)
		(fp_line
			(start -0.7874 0.4064)
			(end 0.7874 0.4064)
			(stroke
				(width 0.1524)
				(type default)
			)
			(layer "B.SilkS")
		)
		(fp_line
			(start -0.7874 -0.4064)
			(end -0.7874 0.4064)
			(stroke
				(width 0.1524)
				(type default)
			)
			(layer "B.SilkS")
		)
		(fp_line
			(start 0.67945 0.3048)
			(end 0.67945 -0.305054)
			(stroke
				(width 0.1)
				(type default)
			)
			(layer "B.Fab")
		)
		(fp_line
			(start 0.67945 -0.305054)
			(end 0.12065 -0.305054)
			(stroke
				(width 0.1)
				(type default)
			)
			(layer "B.Fab")
		)
		(fp_line
			(start 0.12065 0.3048)
			(end 0.67945 0.3048)
			(stroke
				(width 0.1)
				(type default)
			)
			(layer "B.Fab")
		)
		(fp_line
			(start 0.12065 0.2794)
			(end 0.12065 0.3048)
			(stroke
				(width 0.1)
				(type default)
			)
			(layer "B.Fab")
		)
		(fp_line
			(start 0.12065 -0.2794)
			(end -0.12065 -0.2794)
			(stroke
				(width 0.1)
				(type default)
			)
			(layer "B.Fab")
		)
		(fp_line
			(start 0.12065 -0.305054)
			(end 0.12065 -0.2794)
			(stroke
				(width 0.1)
				(type default)
			)
			(layer "B.Fab")
		)
		(fp_line
			(start -0.120396 0.3048)
			(end -0.120396 0.2794)
			(stroke
				(width 0.1)
				(type default)
			)
			(layer "B.Fab")
		)
		(fp_line
			(start -0.120396 0.2794)
			(end 0.12065 0.2794)
			(stroke
				(width 0.1)
				(type default)
			)
			(layer "B.Fab")
		)
		(fp_line
			(start -0.12065 -0.2794)
			(end -0.12065 -0.3048)
			(stroke
				(width 0.1)
				(type default)
			)
			(layer "B.Fab")
		)
		(fp_line
			(start -0.12065 -0.3048)
			(end -0.67945 -0.3048)
			(stroke
				(width 0.1)
				(type default)
			)
			(layer "B.Fab")
		)
		(fp_line
			(start -0.67945 0.3048)
			(end -0.120396 0.3048)
			(stroke
				(width 0.1)
				(type default)
			)
			(layer "B.Fab")
		)
		(fp_line
			(start -0.67945 -0.3048)
			(end -0.67945 0.3048)
			(stroke
				(width 0.1)
				(type default)
			)
			(layer "B.Fab")
		)
		(pad "1" smd circle
			(at 0.40005 0)
			(size 0 0)
			(layers "B.Cu" "B.Mask" "B.Paste")
			(net "PWRGD_PVCCFA_EHV_CPU1_R")
		)
		(pad "2" smd circle
			(at -0.40005 0)
			(size 0 0)
			(layers "B.Cu" "B.Mask" "B.Paste")
			(net "GND")
		)
	)
)
